# T6G (Grand Teton) — schematic netlist excerpt (pin names and nets, part order shuffled) for the footprints in the layout excerpt that follows; sources: Cadence DE-HDL packaged netlist, KiCad conversion of 04192023_DAF0TMB3IC0_F0TG_MB_C_brd_V02_OCP.brd

R6269  Q_RES  0 5% CHIP  pkg 0402LF  page 179 : A = USB_HUB2_TI_VDD_MRP_USB3DN_RXDP4 ; B = P1V2_CPU0_USB2_DVDD12
PR322  Q_RES  5.6 1% CHIP  pkg 0402LF  page 194 : A = SW_PVDDCR_CPU0_P0_BOOT1 ; B = SW_PVDDCR_CPU0_P0_BOOT1_RC

(kicad_pcb
	(version 20260206)
	(generator "pcbnew")
	(generator_version "10.0")
	(general
		(thickness 1.6)
		(legacy_teardrops no)
	)
	(paper "A4")
	(title_block
		(title "04192023_DAF0TMB3IC0_F0TG_MB_C_brd_V02_OCP.brd")
		(comment 1 "Grand Teton / footprints 4396-4397 of 8354")
	)
	(layers
		(0 "F.Cu" signal "TOP")
		(4 "In1.Cu" signal "GND")
		(6 "In2.Cu" signal "IN1")
		(8 "In3.Cu" signal "GND1")
		(10 "In4.Cu" signal "IN2")
		(12 "In5.Cu" signal "GND2")
		(14 "In6.Cu" signal "IN3")
		(16 "In7.Cu" signal "GND3")
		(18 "In8.Cu" signal "VCC")
		(20 "In9.Cu" signal "VCC1")
		(22 "In10.Cu" signal "GND4")
		(24 "In11.Cu" signal "IN4")
		(26 "In12.Cu" signal "GND5")
		(28 "In13.Cu" signal "IN5")
		(30 "In14.Cu" signal "GND6")
		(32 "In15.Cu" signal "IN6")
		(34 "In16.Cu" signal "GND7")
		(2 "B.Cu" signal "BOTTOM")
		(9 "F.Adhes" user "F.Adhesive")
		(11 "B.Adhes" user "B.Adhesive")
		(13 "F.Paste" user "Package Geometry/Pastemask Top")
		(15 "B.Paste" user "Package Geometry/Pastemask Bottom")
		(5 "F.SilkS" user "Ref Des/Silkscreen Top")
		(7 "B.SilkS" user "Ref Des/Silkscreen Bottom")
		(1 "F.Mask" user "Board Geometry/Soldermask Top")
		(3 "B.Mask" user "Board Geometry/Soldermask Bottom")
		(17 "Dwgs.User" user "User.Drawings")
		(19 "Cmts.User" user "User.Comments")
		(21 "Eco1.User" user "User.Eco1")
		(23 "Eco2.User" user "User.Eco2")
		(25 "Edge.Cuts" user "Board Geometry/Outline")
		(27 "Margin" user)
		(31 "F.CrtYd" user "Package Geometry/Place Bound Top")
		(29 "B.CrtYd" user "Package Geometry/Place Bound Bottom")
		(35 "F.Fab" user "Ref Des/Assembly Top")
		(33 "B.Fab" user "Ref Des/Assembly Bottom")
	)
	(footprint ""
		(layer "F.Cu")
		(at 120.69826 -31.405576)
		(property "Reference" "R6269"
			(at 0 0 0)
			(layer "F.SilkS")
			(hide yes)
			(effects
				(font
					(size 1.27 1.27)
				)
			)
		)
		(property "Value" ""
			(at 0 0 0)
			(layer "F.Fab")
			(effects
				(font
					(size 1.27 1.27)
				)
			)
		)
		(duplicate_pad_numbers_are_jumpers no)
		(fp_line
			(start -0.7874 -0.4064)
			(end 0.7874 -0.4064)
			(stroke
				(width 0.1524)
				(type default)
			)
			(layer "F.SilkS")
		)
		(fp_line
			(start -0.7874 0.4064)
			(end -0.7874 -0.4064)
			(stroke
				(width 0.1524)
				(type default)
			)
			(layer "F.SilkS")
		)
		(fp_line
			(start 0.7874 -0.4064)
			(end 0.7874 0.4064)
			(stroke
				(width 0.1524)
				(type default)
			)
			(layer "F.SilkS")
		)
		(fp_line
			(start 0.7874 0.4064)
			(end -0.7874 0.4064)
			(stroke
				(width 0.1524)
				(type default)
			)
			(layer "F.SilkS")
		)
		(fp_line
			(start -0.67945 -0.305054)
			(end -0.12065 -0.305054)
			(stroke
				(width 0.1)
				(type default)
			)
			(layer "F.Fab")
		)
		(fp_line
			(start -0.67945 0.3048)
			(end -0.67945 -0.305054)
			(stroke
				(width 0.1)
				(type default)
			)
			(layer "F.Fab")
		)
		(fp_line
			(start -0.12065 -0.305054)
			(end -0.12065 -0.2794)
			(stroke
				(width 0.1)
				(type default)
			)
			(layer "F.Fab")
		)
		(fp_line
			(start -0.12065 -0.2794)
			(end 0.12065 -0.2794)
			(stroke
				(width 0.1)
				(type default)
			)
			(layer "F.Fab")
		)
		(fp_line
			(start -0.12065 0.2794)
			(end -0.12065 0.3048)
			(stroke
				(width 0.1)
				(type default)
			)
			(layer "F.Fab")
		)
		(fp_line
			(start -0.12065 0.3048)
			(end -0.67945 0.3048)
			(stroke
				(width 0.1)
				(type default)
			)
			(layer "F.Fab")
		)
		(fp_line
			(start 0.120396 0.2794)
			(end -0.12065 0.2794)
			(stroke
				(width 0.1)
				(type default)
			)
			(layer "F.Fab")
		)
		(fp_line
			(start 0.120396 0.3048)
			(end 0.120396 0.2794)
			(stroke
				(width 0.1)
				(type default)
			)
			(layer "F.Fab")
		)
		(fp_line
			(start 0.12065 -0.3048)
			(end 0.67945 -0.3048)
			(stroke
				(width 0.1)
				(type default)
			)
			(layer "F.Fab")
		)
		(fp_line
			(start 0.12065 -0.2794)
			(end 0.12065 -0.3048)
			(stroke
				(width 0.1)
				(type default)
			)
			(layer "F.Fab")
		)
		(fp_line
			(start 0.67945 -0.3048)
			(end 0.67945 0.3048)
			(stroke
				(width 0.1)
				(type default)
			)
			(layer "F.Fab")
		)
		(fp_line
			(start 0.67945 0.3048)
			(end 0.120396 0.3048)
			(stroke
				(width 0.1)
				(type default)
			)
			(layer "F.Fab")
		)
		(pad "1" smd circle
			(at -0.40005 0)
			(size 0 0)
			(layers "F.Cu" "F.Mask" "F.Paste")
			(net "USB_HUB2_TI_VDD_MRP_USB3DN_RXDP4")
		)
		(pad "2" smd circle
			(at 0.40005 0)
			(size 0 0)
			(layers "F.Cu" "F.Mask" "F.Paste")
			(net "P1V2_CPU0_USB2_DVDD12")
		)
	)
	(footprint ""
		(layer "F.Cu")
		(at 363.554772 -173.119542 -90)
		(property "Reference" "PR322"
			(at 0 0 270)
			(layer "F.SilkS")
			(hide yes)
			(effects
				(font
					(size 1.27 1.27)
				)
			)
		)
		(property "Value" ""
			(at 0 0 270)
			(layer "F.Fab")
			(effects
				(font
					(size 1.27 1.27)
				)
			)
		)
		(duplicate_pad_numbers_are_jumpers no)
		(fp_line
			(start -0.7874 0.4064)
			(end -0.7874 -0.4064)
			(stroke
				(width 0.1524)
				(type default)
			)
			(layer "F.SilkS")
		)
		(fp_line
			(start 0.7874 0.4064)
			(end -0.7874 0.4064)
			(stroke
				(width 0.1524)
				(type default)
			)
			(layer "F.SilkS")
		)
		(fp_line
			(start -0.7874 -0.4064)
			(end 0.7874 -0.4064)
			(stroke
				(width 0.1524)
				(type default)
			)
			(layer "F.SilkS")
		)
		(fp_line
			(start 0.7874 -0.4064)
			(end 0.7874 0.4064)
			(stroke
				(width 0.1524)
				(type default)
			)
			(layer "F.SilkS")
		)
		(fp_line
			(start -0.67945 0.3048)
			(end -0.67945 -0.305054)
			(stroke
				(width 0.1)
				(type default)
			)
			(layer "F.Fab")
		)
		(fp_line
			(start -0.12065 0.3048)
			(end -0.67945 0.3048)
			(stroke
				(width 0.1)
				(type default)
			)
			(layer "F.Fab")
		)
		(fp_line
			(start 0.120396 0.3048)
			(end 0.120396 0.2794)
			(stroke
				(width 0.1)
				(type default)
			)
			(layer "F.Fab")
		)
		(fp_line
			(start 0.67945 0.3048)
			(end 0.120396 0.3048)
			(stroke
				(width 0.1)
				(type default)
			)
			(layer "F.Fab")
		)
		(fp_line
			(start -0.12065 0.2794)
			(end -0.12065 0.3048)
			(stroke
				(width 0.1)
				(type default)
			)
			(layer "F.Fab")
		)
		(fp_line
			(start 0.120396 0.2794)
			(end -0.12065 0.2794)
			(stroke
				(width 0.1)
				(type default)
			)
			(layer "F.Fab")
		)
		(fp_line
			(start -0.12065 -0.2794)
			(end 0.12065 -0.2794)
			(stroke
				(width 0.1)
				(type default)
			)
			(layer "F.Fab")
		)
		(fp_line
			(start 0.12065 -0.2794)
			(end 0.12065 -0.3048)
			(stroke
				(width 0.1)
				(type default)
			)
			(layer "F.Fab")
		)
		(fp_line
			(start 0.12065 -0.3048)
			(end 0.67945 -0.3048)
			(stroke
				(width 0.1)
				(type default)
			)
			(layer "F.Fab")
		)
		(fp_line
			(start 0.67945 -0.3048)
			(end 0.67945 0.3048)
			(stroke
				(width 0.1)
				(type default)
			)
			(layer "F.Fab")
		)
		(fp_line
			(start -0.67945 -0.305054)
			(end -0.12065 -0.305054)
			(stroke
				(width 0.1)
				(type default)
			)
			(layer "F.Fab")
		)
		(fp_line
			(start -0.12065 -0.305054)
			(end -0.12065 -0.2794)
			(stroke
				(width 0.1)
				(type default)
			)
			(layer "F.Fab")
		)
		(pad "1" smd circle
			(at -0.40005 0 270)
			(size 0 0)
			(layers "F.Cu" "F.Mask" "F.Paste")
			(net "SW_PVDDCR_CPU0_P0_BOOT1")
		)
		(pad "2" smd circle
			(at 0.40005 0 270)
			(size 0 0)
			(layers "F.Cu" "F.Mask" "F.Paste")
			(net "SW_PVDDCR_CPU0_P0_BOOT1_RC")
		)
	)
)
